(kicad_pcb
	(version 20260206)
	(generator "pcbnew")
	(generator_version "10.0")
	(general
		(thickness 1.6)
		(legacy_teardrops no)
	)
	(paper "A4")
	(title_block
		(title "baseboard — 13948-1b.1110WZS1818.brd")
		(comment 1 "Honey Badger (Wiwynn) / footprints 2354-2361 of 2523")
	)
	(layers
		(0 "F.Cu" signal "TOP")
		(4 "In1.Cu" signal "L2GND")
		(6 "In2.Cu" signal "L3")
		(8 "In3.Cu" signal "L4VCC")
		(10 "In4.Cu" signal "L5VCC")
		(12 "In5.Cu" signal "L6")
		(14 "In6.Cu" signal "L7GND")
		(2 "B.Cu" signal "BOTTOM")
		(9 "F.Adhes" user "F.Adhesive")
		(11 "B.Adhes" user "B.Adhesive")
		(13 "F.Paste" user "Package Geometry/Pastemask Top")
		(15 "B.Paste" user "Package Geometry/Pastemask Bottom")
		(5 "F.SilkS" user "Ref Des/Silkscreen Top")
		(7 "B.SilkS" user "Ref Des/Silkscreen Bottom")
		(1 "F.Mask" user "Board Geometry/Soldermask Top")
		(3 "B.Mask" user "Board Geometry/Soldermask Bottom")
		(17 "Dwgs.User" user "User.Drawings")
		(19 "Cmts.User" user "User.Comments")
		(21 "Eco1.User" user "User.Eco1")
		(23 "Eco2.User" user "User.Eco2")
		(25 "Edge.Cuts" user "Board Geometry/Outline")
		(27 "Margin" user)
		(31 "F.CrtYd" user "Package Geometry/Place Bound Top")
		(29 "B.CrtYd" user "Package Geometry/Place Bound Bottom")
		(35 "F.Fab" user "Ref Des/Assembly Top")
		(33 "B.Fab" user "Ref Des/Assembly Bottom")
	)
	(footprint ""
		(layer "B.Cu")
		(at 350.5962 -71.8058 180)
		(property "Reference" "R295"
			(at 0 0 0)
			(layer "B.SilkS")
			(hide yes)
			(effects
				(font
					(size 1.27 1.27)
				)
				(justify mirror)
			)
		)
		(property "Value" "0R0402-PAD-1-GP"
			(at -0.064008 -3.993896 180)
			(unlocked yes)
			(layer "B.Fab")
			(hide yes)
			(effects
				(font
					(size 1.016 1.016)
					(thickness 0.1524)
				)
				(justify mirror)
			)
		)
		(property "Device Type" "0R0402-PAD"
			(at -0.064008 -5.517896 180)
			(unlocked yes)
			(layer "B.Fab")
			(hide yes)
			(effects
				(font
					(size 1.016 1.016)
					(thickness 0.1524)
				)
				(justify mirror)
			)
		)
		(duplicate_pad_numbers_are_jumpers no)
		(fp_line
			(start 0.508 -0.9398)
			(end 0.508 0.9398)
			(stroke
				(width 0.1524)
				(type default)
			)
			(layer "B.SilkS")
		)
		(fp_line
			(start -0.508 -0.9398)
			(end 0.508 -0.9398)
			(stroke
				(width 0.1524)
				(type default)
			)
			(layer "B.SilkS")
		)
		(fp_rect
			(start 0.508 0.9398)
			(end -0.508 -0.9398)
			(stroke
				(width 0)
				(type default)
			)
			(fill no)
			(layer "B.CrtYd")
		)
		(fp_rect
			(start 0.508 0.9398)
			(end -0.508 -0.9398)
			(stroke
				(width 0)
				(type default)
			)
			(fill no)
			(layer "B.Fab")
		)
		(pad "1" smd custom
			(at 0 -0.4445)
			(size 0.1397 0.1397)
			(layers "B.Cu" "B.Mask" "B.Paste")
			(net "ROMD0_R")
			(options
				(clearance outline)
				(anchor circle)
			)
			(primitives
				(gr_poly
					(pts
						(xy -0.2794 -0.3683)
						(arc
							(start -0.2794 0.2667)
							(mid -0.249642 0.338542)
							(end -0.1778 0.3683)
						)
						(arc
							(start 0.1778 0.3683)
							(mid 0.249642 0.338542)
							(end 0.2794 0.2667)
						)
						(xy 0.2794 -0.3683)
					)
					(width 0)
					(fill yes)
				)
			)
		)
		(pad "2" smd custom
			(at 0 0.4445)
			(size 0.1397 0.1397)
			(layers "B.Cu" "B.Mask" "B.Paste")
			(net "ROMD0")
			(options
				(clearance outline)
				(anchor circle)
			)
			(primitives
				(gr_poly
					(pts
						(arc
							(start -0.1778 -0.3683)
							(mid -0.249642 -0.338542)
							(end -0.2794 -0.2667)
						)
						(xy -0.2794 0.3683) (xy 0.2794 0.3683)
						(arc
							(start 0.2794 -0.2667)
							(mid 0.249642 -0.338542)
							(end 0.1778 -0.3683)
						)
					)
					(width 0)
					(fill yes)
				)
			)
		)
	)
	(footprint ""
		(layer "B.Cu")
		(at 319.913 -164.338 -90)
		(property "Reference" "R438"
			(at 0 0 90)
			(layer "B.SilkS")
			(hide yes)
			(effects
				(font
					(size 1.27 1.27)
				)
				(justify mirror)
			)
		)
		(property "Value" "10KR2F-2-GP"
			(at -0.064008 -3.993896 270)
			(unlocked yes)
			(layer "B.Fab")
			(hide yes)
			(effects
				(font
					(size 1.016 1.016)
					(thickness 0.1524)
				)
				(justify mirror)
			)
		)
		(property "Device Type" "R402H16"
			(at -0.064008 -5.517896 270)
			(unlocked yes)
			(layer "B.Fab")
			(hide yes)
			(effects
				(font
					(size 1.016 1.016)
					(thickness 0.1524)
				)
				(justify mirror)
			)
		)
		(duplicate_pad_numbers_are_jumpers no)
		(fp_line
			(start -0.508 -0.9398)
			(end 0.508 -0.9398)
			(stroke
				(width 0.1524)
				(type default)
			)
			(layer "B.SilkS")
		)
		(fp_line
			(start 0.508 -0.9398)
			(end 0.508 0.9398)
			(stroke
				(width 0.1524)
				(type default)
			)
			(layer "B.SilkS")
		)
		(fp_rect
			(start 0.508 0.9398)
			(end -0.508 -0.9398)
			(stroke
				(width 0)
				(type default)
			)
			(fill no)
			(layer "B.CrtYd")
		)
		(fp_rect
			(start 0.508 0.9398)
			(end -0.508 -0.9398)
			(stroke
				(width 0)
				(type default)
			)
			(fill no)
			(layer "B.Fab")
		)
		(pad "1" smd custom
			(at 0 -0.4445 90)
			(size 0.1397 0.1397)
			(layers "B.Cu" "B.Mask" "B.Paste")
			(net "P3V3_STBY")
			(options
				(clearance outline)
				(anchor circle)
			)
			(primitives
				(gr_poly
					(pts
						(arc
							(start -0.1778 0.2794)
							(mid -0.249642 0.249642)
							(end -0.2794 0.1778)
						)
						(arc
							(start -0.2794 -0.1778)
							(mid -0.249642 -0.249642)
							(end -0.1778 -0.2794)
						)
						(arc
							(start 0.1778 -0.2794)
							(mid 0.249642 -0.249642)
							(end 0.2794 -0.1778)
						)
						(arc
							(start 0.2794 0.1778)
							(mid 0.249642 0.249642)
							(end 0.1778 0.2794)
						)
					)
					(width 0)
					(fill yes)
				)
			)
		)
		(pad "2" smd custom
			(at 0 0.4445 90)
			(size 0.1397 0.1397)
			(layers "B.Cu" "B.Mask" "B.Paste")
			(net "NIC_SMBUS_SDA")
			(options
				(clearance outline)
				(anchor circle)
			)
			(primitives
				(gr_poly
					(pts
						(arc
							(start -0.1778 0.2794)
							(mid -0.249642 0.249642)
							(end -0.2794 0.1778)
						)
						(arc
							(start -0.2794 -0.1778)
							(mid -0.249642 -0.249642)
							(end -0.1778 -0.2794)
						)
						(arc
							(start 0.1778 -0.2794)
							(mid 0.249642 -0.249642)
							(end 0.2794 -0.1778)
						)
						(arc
							(start 0.2794 0.1778)
							(mid 0.249642 0.249642)
							(end 0.1778 0.2794)
						)
					)
					(width 0)
					(fill yes)
				)
			)
		)
	)
	(footprint ""
		(layer "B.Cu")
		(at 105.264966 -46.609 90)
		(property "Reference" "SC1035"
			(at 0 0 90)
			(layer "B.SilkS")
			(hide yes)
			(effects
				(font
					(size 1.27 1.27)
				)
				(justify mirror)
			)
		)
		(property "Value" "SC1KP50V2KX-1GP"
			(at -1.1811 -2.7051 90)
			(unlocked yes)
			(layer "B.Fab")
			(hide yes)
			(effects
				(font
					(size 1.016 1.016)
					(thickness 0.1524)
				)
				(justify mirror)
			)
		)
		(property "Device Type" "C402H22"
			(at -1.1811 -4.2291 90)
			(unlocked yes)
			(layer "B.Fab")
			(hide yes)
			(effects
				(font
					(size 1.016 1.016)
					(thickness 0.1524)
				)
				(justify mirror)
			)
		)
		(duplicate_pad_numbers_are_jumpers no)
		(fp_rect
			(start 0.4318 0.9525)
			(end -0.4318 -0.9525)
			(stroke
				(width 0)
				(type default)
			)
			(fill no)
			(layer "B.CrtYd")
		)
		(fp_rect
			(start 0.4318 0.9525)
			(end -0.4318 -0.9525)
			(stroke
				(width 0)
				(type default)
			)
			(fill no)
			(layer "B.Fab")
		)
		(pad "1" smd custom
			(at 0 -0.4445 270)
			(size 0.1524 0.1524)
			(layers "B.Cu" "B.Mask" "B.Paste")
			(net "P0V955_C")
			(options
				(clearance outline)
				(anchor circle)
			)
			(primitives
				(gr_poly
					(pts
						(arc
							(start 0.3048 0.2032)
							(mid 0.275042 0.275042)
							(end 0.2032 0.3048)
						)
						(arc
							(start -0.2032 0.3048)
							(mid -0.275042 0.275042)
							(end -0.3048 0.2032)
						)
						(arc
							(start -0.3048 -0.2032)
							(mid -0.275042 -0.275042)
							(end -0.2032 -0.3048)
						)
						(arc
							(start 0.2032 -0.3048)
							(mid 0.275042 -0.275042)
							(end 0.3048 -0.2032)
						)
					)
					(width 0)
					(fill yes)
				)
			)
		)
		(pad "2" smd custom
			(at 0 0.4445 270)
			(size 0.1524 0.1524)
			(layers "B.Cu" "B.Mask" "B.Paste")
			(net "GND")
			(options
				(clearance outline)
				(anchor circle)
			)
			(primitives
				(gr_poly
					(pts
						(arc
							(start 0.3048 0.2032)
							(mid 0.275042 0.275042)
							(end 0.2032 0.3048)
						)
						(arc
							(start -0.2032 0.3048)
							(mid -0.275042 0.275042)
							(end -0.3048 0.2032)
						)
						(arc
							(start -0.3048 -0.2032)
							(mid -0.275042 -0.275042)
							(end -0.2032 -0.3048)
						)
						(arc
							(start 0.2032 -0.3048)
							(mid 0.275042 -0.275042)
							(end 0.3048 -0.2032)
						)
					)
					(width 0)
					(fill yes)
				)
			)
		)
	)
	(footprint ""
		(layer "B.Cu")
		(at 114.360198 -50.89525)
		(property "Reference" "STP161"
			(at 0 0 0)
			(layer "B.SilkS")
			(hide yes)
			(effects
				(font
					(size 1.27 1.27)
				)
				(justify mirror)
			)
		)
		(property "Value" "TPAD28"
			(at -0.0127 -1.8034 0)
			(unlocked yes)
			(layer "B.Fab")
			(hide yes)
			(effects
				(font
					(size 1.016 1.016)
					(thickness 0.1524)
				)
				(justify mirror)
			)
		)
		(property "Device Type" "TPAD28"
			(at -0.0127 -3.3274 0)
			(unlocked yes)
			(layer "B.Fab")
			(hide yes)
			(effects
				(font
					(size 1.016 1.016)
					(thickness 0.1524)
				)
				(justify mirror)
			)
		)
		(duplicate_pad_numbers_are_jumpers no)
		(fp_poly
			(pts
				(arc
					(start 0.3556 0)
					(mid -0.3556 0)
					(end 0.3556 0)
				)
			)
			(stroke
				(width 0)
				(type default)
			)
			(fill no)
			(layer "B.CrtYd")
		)
		(fp_poly
			(pts
				(arc
					(start 0.6096 0)
					(mid -0.6096 0)
					(end 0.6096 0)
				)
			)
			(stroke
				(width 0)
				(type default)
			)
			(fill no)
			(layer "B.Fab")
		)
		(pad "1" smd circle
			(at 0 0 180)
			(size 0.7112 0.7112)
			(layers "B.Cu" "B.Mask" "B.Paste")
			(net "XM_ADDR_25")
		)
	)
	(footprint ""
		(layer "B.Cu")
		(at 319.913 -169.545 90)
		(property "Reference" "R436"
			(at 0 0 90)
			(layer "B.SilkS")
			(hide yes)
			(effects
				(font
					(size 1.27 1.27)
				)
				(justify mirror)
			)
		)
		(property "Value" "4K7R2F-GP"
			(at -0.064008 -3.993896 90)
			(unlocked yes)
			(layer "B.Fab")
			(hide yes)
			(effects
				(font
					(size 1.016 1.016)
					(thickness 0.1524)
				)
				(justify mirror)
			)
		)
		(property "Device Type" "R402H16"
			(at -0.064008 -5.517896 90)
			(unlocked yes)
			(layer "B.Fab")
			(hide yes)
			(effects
				(font
					(size 1.016 1.016)
					(thickness 0.1524)
				)
				(justify mirror)
			)
		)
		(duplicate_pad_numbers_are_jumpers no)
		(fp_line
			(start 0.508 -0.9398)
			(end 0.508 0.9398)
			(stroke
				(width 0.1524)
				(type default)
			)
			(layer "B.SilkS")
		)
		(fp_line
			(start -0.508 -0.9398)
			(end 0.508 -0.9398)
			(stroke
				(width 0.1524)
				(type default)
			)
			(layer "B.SilkS")
		)
		(fp_rect
			(start 0.508 0.9398)
			(end -0.508 -0.9398)
			(stroke
				(width 0)
				(type default)
			)
			(fill no)
			(layer "B.CrtYd")
		)
		(fp_rect
			(start 0.508 0.9398)
			(end -0.508 -0.9398)
			(stroke
				(width 0)
				(type default)
			)
			(fill no)
			(layer "B.Fab")
		)
		(pad "1" smd custom
			(at 0 -0.4445 270)
			(size 0.1397 0.1397)
			(layers "B.Cu" "B.Mask" "B.Paste")
			(net "BMC_I2C_A_SDA")
			(options
				(clearance outline)
				(anchor circle)
			)
			(primitives
				(gr_poly
					(pts
						(arc
							(start -0.1778 0.2794)
							(mid -0.249642 0.249642)
							(end -0.2794 0.1778)
						)
						(arc
							(start -0.2794 -0.1778)
							(mid -0.249642 -0.249642)
							(end -0.1778 -0.2794)
						)
						(arc
							(start 0.1778 -0.2794)
							(mid 0.249642 -0.249642)
							(end 0.2794 -0.1778)
						)
						(arc
							(start 0.2794 0.1778)
							(mid 0.249642 0.249642)
							(end 0.1778 0.2794)
						)
					)
					(width 0)
					(fill yes)
				)
			)
		)
		(pad "2" smd custom
			(at 0 0.4445 270)
			(size 0.1397 0.1397)
			(layers "B.Cu" "B.Mask" "B.Paste")
			(net "P3V3_STBY")
			(options
				(clearance outline)
				(anchor circle)
			)
			(primitives
				(gr_poly
					(pts
						(arc
							(start -0.1778 0.2794)
							(mid -0.249642 0.249642)
							(end -0.2794 0.1778)
						)
						(arc
							(start -0.2794 -0.1778)
							(mid -0.249642 -0.249642)
							(end -0.1778 -0.2794)
						)
						(arc
							(start 0.1778 -0.2794)
							(mid 0.249642 -0.249642)
							(end 0.2794 -0.1778)
						)
						(arc
							(start 0.2794 0.1778)
							(mid 0.249642 0.249642)
							(end 0.1778 0.2794)
						)
					)
					(width 0)
					(fill yes)
				)
			)
		)
	)
	(footprint ""
		(layer "B.Cu")
		(at 289.306 -172.3644)
		(property "Reference" "TP182"
			(at 0 0 0)
			(layer "B.SilkS")
			(hide yes)
			(effects
				(font
					(size 1.27 1.27)
				)
				(justify mirror)
			)
		)
		(property "Value" "TPAD28"
			(at -0.0127 -1.8034 0)
			(unlocked yes)
			(layer "B.Fab")
			(hide yes)
			(effects
				(font
					(size 1.016 1.016)
					(thickness 0.1524)
				)
				(justify mirror)
			)
		)
		(property "Device Type" "TPAD28"
			(at -0.0127 -3.3274 0)
			(unlocked yes)
			(layer "B.Fab")
			(hide yes)
			(effects
				(font
					(size 1.016 1.016)
					(thickness 0.1524)
				)
				(justify mirror)
			)
		)
		(duplicate_pad_numbers_are_jumpers no)
		(fp_poly
			(pts
				(arc
					(start 0.3556 0)
					(mid -0.3556 0)
					(end 0.3556 0)
				)
			)
			(stroke
				(width 0)
				(type default)
			)
			(fill no)
			(layer "B.CrtYd")
		)
		(fp_poly
			(pts
				(arc
					(start 0.6096 0)
					(mid -0.6096 0)
					(end 0.6096 0)
				)
			)
			(stroke
				(width 0)
				(type default)
			)
			(fill no)
			(layer "B.Fab")
		)
		(pad "1" smd circle
			(at 0 0 180)
			(size 0.7112 0.7112)
			(layers "B.Cu" "B.Mask" "B.Paste")
			(net "TP_BMC_GPIOF6")
		)
	)
	(footprint ""
		(layer "B.Cu")
		(at 317.5 -181.737 -90)
		(property "Reference" "R373"
			(at 0 0 90)
			(layer "B.SilkS")
			(hide yes)
			(effects
				(font
					(size 1.27 1.27)
				)
				(justify mirror)
			)
		)
		(property "Value" "0R2J-2-GP"
			(at -0.064008 -3.993896 270)
			(unlocked yes)
			(layer "B.Fab")
			(hide yes)
			(effects
				(font
					(size 1.016 1.016)
					(thickness 0.1524)
				)
				(justify mirror)
			)
		)
		(property "Device Type" "R402H16"
			(at -0.064008 -5.517896 270)
			(unlocked yes)
			(layer "B.Fab")
			(hide yes)
			(effects
				(font
					(size 1.016 1.016)
					(thickness 0.1524)
				)
				(justify mirror)
			)
		)
		(duplicate_pad_numbers_are_jumpers no)
		(fp_line
			(start -0.508 -0.9398)
			(end 0.508 -0.9398)
			(stroke
				(width 0.1524)
				(type default)
			)
			(layer "B.SilkS")
		)
		(fp_line
			(start 0.508 -0.9398)
			(end 0.508 0.9398)
			(stroke
				(width 0.1524)
				(type default)
			)
			(layer "B.SilkS")
		)
		(fp_rect
			(start 0.508 0.9398)
			(end -0.508 -0.9398)
			(stroke
				(width 0)
				(type default)
			)
			(fill no)
			(layer "B.CrtYd")
		)
		(fp_rect
			(start 0.508 0.9398)
			(end -0.508 -0.9398)
			(stroke
				(width 0)
				(type default)
			)
			(fill no)
			(layer "B.Fab")
		)
		(pad "1" smd custom
			(at 0 -0.4445 90)
			(size 0.1397 0.1397)
			(layers "B.Cu" "B.Mask" "B.Paste")
			(net "ADC_P1V5_E")
			(options
				(clearance outline)
				(anchor circle)
			)
			(primitives
				(gr_poly
					(pts
						(arc
							(start -0.1778 0.2794)
							(mid -0.249642 0.249642)
							(end -0.2794 0.1778)
						)
						(arc
							(start -0.2794 -0.1778)
							(mid -0.249642 -0.249642)
							(end -0.1778 -0.2794)
						)
						(arc
							(start 0.1778 -0.2794)
							(mid 0.249642 -0.249642)
							(end 0.2794 -0.1778)
						)
						(arc
							(start 0.2794 0.1778)
							(mid 0.249642 0.249642)
							(end 0.1778 0.2794)
						)
					)
					(width 0)
					(fill yes)
				)
			)
		)
		(pad "2" smd custom
			(at 0 0.4445 90)
			(size 0.1397 0.1397)
			(layers "B.Cu" "B.Mask" "B.Paste")
			(net "ADC_P1V5_E_BMC")
			(options
				(clearance outline)
				(anchor circle)
			)
			(primitives
				(gr_poly
					(pts
						(arc
							(start -0.1778 0.2794)
							(mid -0.249642 0.249642)
							(end -0.2794 0.1778)
						)
						(arc
							(start -0.2794 -0.1778)
							(mid -0.249642 -0.249642)
							(end -0.1778 -0.2794)
						)
						(arc
							(start 0.1778 -0.2794)
							(mid 0.249642 -0.249642)
							(end 0.2794 -0.1778)
						)
						(arc
							(start 0.2794 0.1778)
							(mid 0.249642 0.249642)
							(end 0.1778 0.2794)
						)
					)
					(width 0)
					(fill yes)
				)
			)
		)
	)
	(footprint ""
		(layer "B.Cu")
		(at 123.298966 -42.164 90)
		(property "Reference" "SC994"
			(at 0 0 90)
			(layer "B.SilkS")
			(hide yes)
			(effects
				(font
					(size 1.27 1.27)
				)
				(justify mirror)
			)
		)
		(property "Value" "SCD1U16V2KX-3GP"
			(at -1.1811 -2.7051 90)
			(unlocked yes)
			(layer "B.Fab")
			(hide yes)
			(effects
				(font
					(size 1.016 1.016)
					(thickness 0.1524)
				)
				(justify mirror)
			)
		)
		(property "Device Type" "C402H22"
			(at -1.1811 -4.2291 90)
			(unlocked yes)
			(layer "B.Fab")
			(hide yes)
			(effects
				(font
					(size 1.016 1.016)
					(thickness 0.1524)
				)
				(justify mirror)
			)
		)
		(duplicate_pad_numbers_are_jumpers no)
		(fp_rect
			(start 0.4318 0.9525)
			(end -0.4318 -0.9525)
			(stroke
				(width 0)
				(type default)
			)
			(fill no)
			(layer "B.CrtYd")
		)
		(fp_rect
			(start 0.4318 0.9525)
			(end -0.4318 -0.9525)
			(stroke
				(width 0)
				(type default)
			)
			(fill no)
			(layer "B.Fab")
		)
		(pad "1" smd custom
			(at 0 -0.4445 270)
			(size 0.1524 0.1524)
			(layers "B.Cu" "B.Mask" "B.Paste")
			(net "P1V8_C")
			(options
				(clearance outline)
				(anchor circle)
			)
			(primitives
				(gr_poly
					(pts
						(arc
							(start 0.3048 0.2032)
							(mid 0.275042 0.275042)
							(end 0.2032 0.3048)
						)
						(arc
							(start -0.2032 0.3048)
							(mid -0.275042 0.275042)
							(end -0.3048 0.2032)
						)
						(arc
							(start -0.3048 -0.2032)
							(mid -0.275042 -0.275042)
							(end -0.2032 -0.3048)
						)
						(arc
							(start 0.2032 -0.3048)
							(mid 0.275042 -0.275042)
							(end 0.3048 -0.2032)
						)
					)
					(width 0)
					(fill yes)
				)
			)
		)
		(pad "2" smd custom
			(at 0 0.4445 270)
			(size 0.1524 0.1524)
			(layers "B.Cu" "B.Mask" "B.Paste")
			(net "GND")
			(options
				(clearance outline)
				(anchor circle)
			)
			(primitives
				(gr_poly
					(pts
						(arc
							(start 0.3048 0.2032)
							(mid 0.275042 0.275042)
							(end 0.2032 0.3048)
						)
						(arc
							(start -0.2032 0.3048)
							(mid -0.275042 0.275042)
							(end -0.3048 0.2032)
						)
						(arc
							(start -0.3048 -0.2032)
							(mid -0.275042 -0.275042)
							(end -0.2032 -0.3048)
						)
						(arc
							(start 0.2032 -0.3048)
							(mid 0.275042 -0.275042)
							(end 0.3048 -0.2032)
						)
					)
					(width 0)
					(fill yes)
				)
			)
		)
	)
)
